# BASEBOARD_FAB2 (Tioga Pass) — schematic netlist excerpt (pin names and nets, part order shuffled) for the footprints in the layout excerpt that follows; sources: Cadence DE-HDL packaged netlist, KiCad conversion of Wiwynn_Tioga_Pass_MB.brd

R1W4  RES  10.0K 1% CHIP  pkg 0402  page 250 : A = FM_OCP_MEZZB_PRES_LVT3_BMC ; B = P3V3_STBY
R2N24  RES  1.00K 1% EMPTY  pkg 0402  page 135 : A = FM_QAT_EN_N ; B = GND
C5M4  CAP_A  47UF 4V 20% X5R  pkg 0603V  page 220 : A = PVDDQ_DEF ; B = GND

(kicad_pcb
	(version 20260206)
	(generator "pcbnew")
	(generator_version "10.0")
	(general
		(thickness 1.6)
		(legacy_teardrops no)
	)
	(paper "A4")
	(title_block
		(title "Wiwynn_Tioga_Pass_MB.brd")
		(comment 1 "Tioga Pass / footprints 3031-3033 of 4770")
	)
	(layers
		(0 "F.Cu" signal "TOP")
		(4 "In1.Cu" signal "L2GND")
		(6 "In2.Cu" signal "L3")
		(8 "In3.Cu" signal "L4GND")
		(10 "In4.Cu" signal "L5")
		(12 "In5.Cu" signal "L6GND")
		(14 "In6.Cu" signal "L7VCC")
		(16 "In7.Cu" signal "L8VCC")
		(18 "In8.Cu" signal "L9GND")
		(20 "In9.Cu" signal "L10")
		(22 "In10.Cu" signal "L11GND")
		(24 "In11.Cu" signal "L12")
		(26 "In12.Cu" signal "L13GND")
		(2 "B.Cu" signal "BOTTOM")
		(9 "F.Adhes" user "F.Adhesive")
		(11 "B.Adhes" user "B.Adhesive")
		(13 "F.Paste" user "Package Geometry/Pastemask Top")
		(15 "B.Paste" user "Package Geometry/Pastemask Bottom")
		(5 "F.SilkS" user "Ref Des/Silkscreen Top")
		(7 "B.SilkS" user "Ref Des/Silkscreen Bottom")
		(1 "F.Mask" user "Board Geometry/Soldermask Top")
		(3 "B.Mask" user "Board Geometry/Soldermask Bottom")
		(17 "Dwgs.User" user "User.Drawings")
		(19 "Cmts.User" user "User.Comments")
		(21 "Eco1.User" user "User.Eco1")
		(23 "Eco2.User" user "User.Eco2")
		(25 "Edge.Cuts" user "Board Geometry/Outline")
		(27 "Margin" user)
		(31 "F.CrtYd" user "Package Geometry/Place Bound Top")
		(29 "B.CrtYd" user "Package Geometry/Place Bound Bottom")
		(35 "F.Fab" user "Ref Des/Assembly Top")
		(33 "B.Fab" user "Ref Des/Assembly Bottom")
	)
	(footprint ""
		(layer "B.Cu")
		(at 407.86304 -56.15686 180)
		(property "Reference" "R1W4"
			(at 0.8382 -0.67818 180)
			(unlocked yes)
			(layer "B.SilkS")
			(effects
				(font
					(size 0.4064 0.254)
					(thickness 0.1524)
				)
				(justify left mirror)
			)
		)
		(property "Value" ""
			(at 0 0 0)
			(layer "B.Fab")
			(effects
				(font
					(size 1.27 1.27)
				)
				(justify mirror)
			)
		)
		(duplicate_pad_numbers_are_jumpers no)
		(fp_poly
			(pts
				(xy 0.2794 -0.1016) (xy -0.2794 -0.1016) (xy -0.2794 0.9906) (xy 0.2794 0.9906)
			)
			(stroke
				(width 0)
				(type default)
			)
			(fill no)
			(layer "B.CrtYd")
		)
		(fp_line
			(start 0.2794 0.9906)
			(end -0.2794 0.9906)
			(stroke
				(width 0.1)
				(type default)
			)
			(layer "B.Fab")
		)
		(fp_line
			(start 0.2794 -0.1016)
			(end 0.2794 0.9906)
			(stroke
				(width 0.1)
				(type default)
			)
			(layer "B.Fab")
		)
		(fp_line
			(start -0.2794 0.9906)
			(end -0.2794 -0.1016)
			(stroke
				(width 0.1)
				(type default)
			)
			(layer "B.Fab")
		)
		(fp_line
			(start -0.2794 -0.1016)
			(end 0.2794 -0.1016)
			(stroke
				(width 0.1)
				(type default)
			)
			(layer "B.Fab")
		)
		(pad "1" smd rect
			(at 0 0)
			(size 0.508 0.508)
			(layers "B.Cu" "B.Mask" "B.Paste")
			(net "FM_OCP_MEZZB_PRES_LVT3_BMC")
		)
		(pad "2" smd rect
			(at 0 0.889)
			(size 0.508 0.508)
			(layers "B.Cu" "B.Mask" "B.Paste")
			(net "P3V3_STBY")
		)
		(zone
			(layer "B.Cu")
			(hatch none 0.5)
			(connect_pads
				(clearance 0)
			)
			(min_thickness 0.25)
			(keepout
				(tracks not_allowed)
				(vias allowed)
				(pads allowed)
				(copperpour not_allowed)
				(footprints allowed)
			)
			(placement
				(enabled no)
				(sheetname "")
			)
			(fill
				(thermal_gap 0.5)
				(thermal_bridge_width 0.5)
				(island_removal_mode 0)
			)
			(polygon
				(pts
					(xy 407.60904 -56.79186) (xy 408.11704 -56.79186) (xy 408.11704 -56.41086) (xy 407.60904 -56.41086)
				)
			)
		)
		(zone
			(layer "B.Cu")
			(hatch none 0.5)
			(connect_pads
				(clearance 0)
			)
			(min_thickness 0.25)
			(keepout
				(tracks allowed)
				(vias not_allowed)
				(pads allowed)
				(copperpour not_allowed)
				(footprints allowed)
			)
			(placement
				(enabled no)
				(sheetname "")
			)
			(fill
				(thermal_gap 0.5)
				(thermal_bridge_width 0.5)
				(island_removal_mode 0)
			)
			(polygon
				(pts
					(xy 407.60904 -56.41086) (xy 408.11704 -56.41086) (xy 408.11704 -56.79186) (xy 407.60904 -56.79186)
				)
			)
		)
	)
	(footprint ""
		(layer "B.Cu")
		(at 403.568408 -93.755718 -90)
		(property "Reference" "R2N24"
			(at 0 0 90)
			(layer "B.SilkS")
			(hide yes)
			(effects
				(font
					(size 1.27 1.27)
				)
				(justify mirror)
			)
		)
		(property "Value" ""
			(at 0 0 90)
			(layer "B.Fab")
			(effects
				(font
					(size 1.27 1.27)
				)
				(justify mirror)
			)
		)
		(duplicate_pad_numbers_are_jumpers no)
		(fp_poly
			(pts
				(xy 0.2794 -0.1016) (xy -0.2794 -0.1016) (xy -0.2794 0.9906) (xy 0.2794 0.9906)
			)
			(stroke
				(width 0)
				(type default)
			)
			(fill no)
			(layer "B.CrtYd")
		)
		(fp_line
			(start -0.2794 0.9906)
			(end -0.2794 -0.1016)
			(stroke
				(width 0.1)
				(type default)
			)
			(layer "B.Fab")
		)
		(fp_line
			(start 0.2794 0.9906)
			(end -0.2794 0.9906)
			(stroke
				(width 0.1)
				(type default)
			)
			(layer "B.Fab")
		)
		(fp_line
			(start -0.2794 -0.1016)
			(end 0.2794 -0.1016)
			(stroke
				(width 0.1)
				(type default)
			)
			(layer "B.Fab")
		)
		(fp_line
			(start 0.2794 -0.1016)
			(end 0.2794 0.9906)
			(stroke
				(width 0.1)
				(type default)
			)
			(layer "B.Fab")
		)
		(pad "1" smd rect
			(at 0 0 90)
			(size 0.508 0.508)
			(layers "B.Cu" "B.Mask" "B.Paste")
			(net "FM_QAT_EN_N")
		)
		(pad "2" smd rect
			(at 0 0.889 90)
			(size 0.508 0.508)
			(layers "B.Cu" "B.Mask" "B.Paste")
			(net "GND")
		)
		(zone
			(layer "B.Cu")
			(hatch none 0.5)
			(connect_pads
				(clearance 0)
			)
			(min_thickness 0.25)
			(keepout
				(tracks not_allowed)
				(vias allowed)
				(pads allowed)
				(copperpour not_allowed)
				(footprints allowed)
			)
			(placement
				(enabled no)
				(sheetname "")
			)
			(fill
				(thermal_gap 0.5)
				(thermal_bridge_width 0.5)
				(island_removal_mode 0)
			)
			(polygon
				(pts
					(xy 402.933408 -93.501718) (xy 402.933408 -94.009718) (xy 403.314408 -94.009718) (xy 403.314408 -93.501718)
				)
			)
		)
		(zone
			(layer "B.Cu")
			(hatch none 0.5)
			(connect_pads
				(clearance 0)
			)
			(min_thickness 0.25)
			(keepout
				(tracks allowed)
				(vias not_allowed)
				(pads allowed)
				(copperpour not_allowed)
				(footprints allowed)
			)
			(placement
				(enabled no)
				(sheetname "")
			)
			(fill
				(thermal_gap 0.5)
				(thermal_bridge_width 0.5)
				(island_removal_mode 0)
			)
			(polygon
				(pts
					(xy 403.314408 -93.501718) (xy 403.314408 -94.009718) (xy 402.933408 -94.009718) (xy 402.933408 -93.501718)
				)
			)
		)
	)
	(footprint ""
		(layer "B.Cu")
		(at 253.392432 -135.4074 90)
		(property "Reference" "C5M4"
			(at -1.848866 0.752348 90)
			(unlocked yes)
			(layer "B.SilkS")
			(effects
				(font
					(size 1.27 0.9652)
					(thickness 0.1524)
				)
				(justify mirror)
			)
		)
		(property "Value" ""
			(at 0 0 90)
			(layer "B.Fab")
			(effects
				(font
					(size 1.27 1.27)
				)
				(justify mirror)
			)
		)
		(duplicate_pad_numbers_are_jumpers no)
		(fp_rect
			(start 0.500126 1.598422)
			(end -0.500126 -0.201422)
			(stroke
				(width 0)
				(type default)
			)
			(fill no)
			(layer "B.CrtYd")
		)
		(fp_line
			(start 0.500126 -0.201422)
			(end -0.500126 -0.201422)
			(stroke
				(width 0.1)
				(type default)
			)
			(layer "B.Fab")
		)
		(fp_line
			(start -0.500126 -0.201422)
			(end -0.500126 1.598422)
			(stroke
				(width 0.1)
				(type default)
			)
			(layer "B.Fab")
		)
		(fp_line
			(start 0.500126 1.598422)
			(end 0.500126 -0.201422)
			(stroke
				(width 0.1)
				(type default)
			)
			(layer "B.Fab")
		)
		(fp_line
			(start -0.500126 1.598422)
			(end 0.500126 1.598422)
			(stroke
				(width 0.1)
				(type default)
			)
			(layer "B.Fab")
		)
		(pad "1" smd rect
			(at 0 0)
			(size 0.889 0.9906)
			(layers "B.Cu" "B.Mask" "B.Paste")
			(net "PVDDQ_DEF")
		)
		(pad "2" smd rect
			(at 0 1.397)
			(size 0.889 0.9906)
			(layers "B.Cu" "B.Mask" "B.Paste")
			(net "GND")
		)
		(zone
			(layer "B.Cu")
			(hatch none 0.5)
			(connect_pads
				(clearance 0)
			)
			(min_thickness 0.25)
			(keepout
				(tracks not_allowed)
				(vias allowed)
				(pads allowed)
				(copperpour not_allowed)
				(footprints allowed)
			)
			(placement
				(enabled no)
				(sheetname "")
			)
			(fill
				(thermal_gap 0.5)
				(thermal_bridge_width 0.5)
				(island_removal_mode 0)
			)
			(polygon
				(pts
					(xy 254.344932 -135.9027) (xy 253.836932 -135.9027) (xy 253.836932 -134.9121) (xy 254.344932 -134.9121)
				)
			)
		)
		(zone
			(layer "B.Cu")
			(hatch none 0.5)
			(connect_pads
				(clearance 0)
			)
			(min_thickness 0.25)
			(keepout
				(tracks allowed)
				(vias not_allowed)
				(pads allowed)
				(copperpour not_allowed)
				(footprints allowed)
			)
			(placement
				(enabled no)
				(sheetname "")
			)
			(fill
				(thermal_gap 0.5)
				(thermal_bridge_width 0.5)
				(island_removal_mode 0)
			)
			(polygon
				(pts
					(xy 254.344932 -135.9027) (xy 253.836932 -135.9027) (xy 253.836932 -134.9121) (xy 254.344932 -134.9121)
				)
			)
		)
	)
)
